(kicad_pcb
	(version 20260206)
	(generator "pcbnew")
	(generator_version "10.0")
	(general
		(thickness 1.6)
		(legacy_teardrops no)
	)
	(paper "A4")
	(title_block
		(title "dpb — 14545-sa.0730WZS0815.brd")
		(comment 1 "Honey Badger (Wiwynn) / footprints 73-79 of 1066")
	)
	(layers
		(0 "F.Cu" signal "TOP")
		(4 "In1.Cu" signal "L2GND")
		(6 "In2.Cu" signal "L3")
		(8 "In3.Cu" signal "L4VCC")
		(10 "In4.Cu" signal "L5VCC")
		(12 "In5.Cu" signal "L6")
		(14 "In6.Cu" signal "L7GND")
		(2 "B.Cu" signal "BOTTOM")
		(9 "F.Adhes" user "F.Adhesive")
		(11 "B.Adhes" user "B.Adhesive")
		(13 "F.Paste" user "Package Geometry/Pastemask Top")
		(15 "B.Paste" user "Package Geometry/Pastemask Bottom")
		(5 "F.SilkS" user "Ref Des/Silkscreen Top")
		(7 "B.SilkS" user "Ref Des/Silkscreen Bottom")
		(1 "F.Mask" user "Board Geometry/Soldermask Top")
		(3 "B.Mask" user "Board Geometry/Soldermask Bottom")
		(17 "Dwgs.User" user "User.Drawings")
		(19 "Cmts.User" user "User.Comments")
		(21 "Eco1.User" user "User.Eco1")
		(23 "Eco2.User" user "User.Eco2")
		(25 "Edge.Cuts" user "Board Geometry/Outline")
		(27 "Margin" user)
		(31 "F.CrtYd" user "Package Geometry/Place Bound Top")
		(29 "B.CrtYd" user "Package Geometry/Place Bound Bottom")
		(35 "F.Fab" user "Ref Des/Assembly Top")
		(33 "B.Fab" user "Ref Des/Assembly Bottom")
	)
	(footprint ""
		(layer "F.Cu")
		(at 42.500042 -350.160082 180)
		(property "Reference" "LED7"
			(at 0 0 180)
			(layer "F.SilkS")
			(hide yes)
			(effects
				(font
					(size 1.27 1.27)
				)
			)
		)
		(property "Value" "LED-RB-4-GP"
			(at 5.88899 1.80848 180)
			(unlocked yes)
			(layer "F.Fab")
			(hide yes)
			(effects
				(font
					(size 1.016 1.016)
					(thickness 0.1524)
				)
			)
		)
		(property "Device Type" "LED1613-4PH20"
			(at 5.88899 0.28448 180)
			(unlocked yes)
			(layer "F.Fab")
			(hide yes)
			(effects
				(font
					(size 1.016 1.016)
					(thickness 0.1524)
				)
			)
		)
		(duplicate_pad_numbers_are_jumpers no)
		(fp_line
			(start 1.4478 0.9652)
			(end -1.4478 0.9652)
			(stroke
				(width 0.1524)
				(type default)
			)
			(layer "F.SilkS")
		)
		(fp_line
			(start 1.4478 -0.9652)
			(end 1.4478 0.9652)
			(stroke
				(width 0.1524)
				(type default)
			)
			(layer "F.SilkS")
		)
		(fp_line
			(start -1.4478 0.9652)
			(end -1.4478 -0.9652)
			(stroke
				(width 0.1524)
				(type default)
			)
			(layer "F.SilkS")
		)
		(fp_line
			(start -1.4478 0.9652)
			(end -1.4478 -0.9652)
			(stroke
				(width 0.508)
				(type default)
			)
			(layer "F.SilkS")
		)
		(fp_line
			(start -1.4478 -0.9652)
			(end 1.4478 -0.9652)
			(stroke
				(width 0.1524)
				(type default)
			)
			(layer "F.SilkS")
		)
		(fp_rect
			(start -0.8001 0.6477)
			(end 0.8001 -0.6477)
			(stroke
				(width 0)
				(type default)
			)
			(fill no)
			(layer "F.CrtYd")
		)
		(fp_poly
			(pts
				(xy -1.7018 1.2192) (xy -1.7018 -0.06223) (xy -0.8001 -0.06223) (xy -0.8001 0.6477) (xy 0.8001 0.6477)
				(xy 0.8001 -0.6477) (xy -0.8001 -0.6477) (xy -0.8001 -0.0635) (xy -1.7018 -0.0635) (xy -1.7018 -1.2192)
				(xy 1.7018 -1.2192) (xy 1.7018 1.2192)
			)
			(stroke
				(width 0)
				(type default)
			)
			(fill no)
			(layer "F.CrtYd")
		)
		(fp_rect
			(start -1.7018 1.2192)
			(end 1.7018 -1.2192)
			(stroke
				(width 0)
				(type default)
			)
			(fill no)
			(layer "F.Fab")
		)
		(pad "1" smd rect
			(at -0.73025 0.4064 180)
			(size 0.9144 0.6096)
			(layers "F.Cu" "F.Mask" "F.Paste")
			(net "DRV_ACT_NET6")
		)
		(pad "2" smd rect
			(at -0.73025 -0.4064 180)
			(size 0.9144 0.6096)
			(layers "F.Cu" "F.Mask" "F.Paste")
			(net "FLT_NET_HDD6")
		)
		(pad "3" smd rect
			(at 0.73025 -0.4064 180)
			(size 0.9144 0.6096)
			(layers "F.Cu" "F.Mask" "F.Paste")
			(net "FLT_HDD6")
		)
		(pad "4" smd rect
			(at 0.73025 0.4064 180)
			(size 0.9144 0.6096)
			(layers "F.Cu" "F.Mask" "F.Paste")
			(net "DRV_ACT_6")
		)
	)
	(footprint ""
		(layer "F.Cu")
		(at 187.464446 -458.885036 90)
		(property "Reference" "R346"
			(at 0 0 90)
			(layer "F.SilkS")
			(hide yes)
			(effects
				(font
					(size 1.27 1.27)
				)
			)
		)
		(property "Value" "4K7R2J-2-GP"
			(at 0.064008 -3.993896 90)
			(unlocked yes)
			(layer "F.Fab")
			(hide yes)
			(effects
				(font
					(size 1.016 1.016)
					(thickness 0.1524)
				)
			)
		)
		(property "Device Type" "R402H16"
			(at 0.064008 -5.517896 90)
			(unlocked yes)
			(layer "F.Fab")
			(hide yes)
			(effects
				(font
					(size 1.016 1.016)
					(thickness 0.1524)
				)
			)
		)
		(duplicate_pad_numbers_are_jumpers no)
		(fp_line
			(start 0.508 -0.9398)
			(end -0.508 -0.9398)
			(stroke
				(width 0.1524)
				(type default)
			)
			(layer "F.SilkS")
		)
		(fp_line
			(start -0.508 -0.9398)
			(end -0.508 0.9398)
			(stroke
				(width 0.1524)
				(type default)
			)
			(layer "F.SilkS")
		)
		(fp_rect
			(start -0.508 0.9398)
			(end 0.508 -0.9398)
			(stroke
				(width 0)
				(type default)
			)
			(fill no)
			(layer "F.CrtYd")
		)
		(fp_rect
			(start -0.508 0.9398)
			(end 0.508 -0.9398)
			(stroke
				(width 0)
				(type default)
			)
			(fill no)
			(layer "F.Fab")
		)
		(pad "1" smd custom
			(at 0 -0.4445 90)
			(size 0.1397 0.1397)
			(layers "F.Cu" "F.Mask" "F.Paste")
			(net "P3V3")
			(options
				(clearance outline)
				(anchor circle)
			)
			(primitives
				(gr_poly
					(pts
						(arc
							(start -0.1778 -0.2794)
							(mid -0.249642 -0.249642)
							(end -0.2794 -0.1778)
						)
						(arc
							(start -0.2794 0.1778)
							(mid -0.249642 0.249642)
							(end -0.1778 0.2794)
						)
						(arc
							(start 0.1778 0.2794)
							(mid 0.249642 0.249642)
							(end 0.2794 0.1778)
						)
						(arc
							(start 0.2794 -0.1778)
							(mid 0.249642 -0.249642)
							(end 0.1778 -0.2794)
						)
					)
					(width 0)
					(fill yes)
				)
			)
		)
		(pad "2" smd custom
			(at 0 0.4445 90)
			(size 0.1397 0.1397)
			(layers "F.Cu" "F.Mask" "F.Paste")
			(net "EEPROM_A1")
			(options
				(clearance outline)
				(anchor circle)
			)
			(primitives
				(gr_poly
					(pts
						(arc
							(start -0.1778 -0.2794)
							(mid -0.249642 -0.249642)
							(end -0.2794 -0.1778)
						)
						(arc
							(start -0.2794 0.1778)
							(mid -0.249642 0.249642)
							(end -0.1778 0.2794)
						)
						(arc
							(start 0.1778 0.2794)
							(mid 0.249642 0.249642)
							(end 0.2794 0.1778)
						)
						(arc
							(start 0.2794 -0.1778)
							(mid 0.249642 -0.249642)
							(end 0.1778 -0.2794)
						)
					)
					(width 0)
					(fill yes)
				)
			)
		)
	)
	(footprint ""
		(layer "F.Cu")
		(at 29.654246 -384.0099)
		(property "Reference" "R310"
			(at 0 0 0)
			(layer "F.SilkS")
			(hide yes)
			(effects
				(font
					(size 1.27 1.27)
				)
			)
		)
		(property "Value" "0R2J-2-GP"
			(at 0.064008 -3.993896 0)
			(unlocked yes)
			(layer "F.Fab")
			(hide yes)
			(effects
				(font
					(size 1.016 1.016)
					(thickness 0.1524)
				)
			)
		)
		(property "Device Type" "R402H16"
			(at 0.064008 -5.517896 0)
			(unlocked yes)
			(layer "F.Fab")
			(hide yes)
			(effects
				(font
					(size 1.016 1.016)
					(thickness 0.1524)
				)
			)
		)
		(duplicate_pad_numbers_are_jumpers no)
		(fp_line
			(start -0.508 -0.9398)
			(end -0.508 0.9398)
			(stroke
				(width 0.1524)
				(type default)
			)
			(layer "F.SilkS")
		)
		(fp_line
			(start 0.508 -0.9398)
			(end -0.508 -0.9398)
			(stroke
				(width 0.1524)
				(type default)
			)
			(layer "F.SilkS")
		)
		(fp_rect
			(start -0.508 0.9398)
			(end 0.508 -0.9398)
			(stroke
				(width 0)
				(type default)
			)
			(fill no)
			(layer "F.CrtYd")
		)
		(fp_rect
			(start -0.508 0.9398)
			(end 0.508 -0.9398)
			(stroke
				(width 0)
				(type default)
			)
			(fill no)
			(layer "F.Fab")
		)
		(pad "1" smd custom
			(at 0 -0.4445)
			(size 0.1397 0.1397)
			(layers "F.Cu" "F.Mask" "F.Paste")
			(net "I2C_B_SDA")
			(options
				(clearance outline)
				(anchor circle)
			)
			(primitives
				(gr_poly
					(pts
						(arc
							(start -0.1778 -0.2794)
							(mid -0.249642 -0.249642)
							(end -0.2794 -0.1778)
						)
						(arc
							(start -0.2794 0.1778)
							(mid -0.249642 0.249642)
							(end -0.1778 0.2794)
						)
						(arc
							(start 0.1778 0.2794)
							(mid 0.249642 0.249642)
							(end 0.2794 0.1778)
						)
						(arc
							(start 0.2794 -0.1778)
							(mid 0.249642 -0.249642)
							(end 0.1778 -0.2794)
						)
					)
					(width 0)
					(fill yes)
				)
			)
		)
		(pad "2" smd custom
			(at 0 0.4445)
			(size 0.1397 0.1397)
			(layers "F.Cu" "F.Mask" "F.Paste")
			(net "TMP1_SDA")
			(options
				(clearance outline)
				(anchor circle)
			)
			(primitives
				(gr_poly
					(pts
						(arc
							(start -0.1778 -0.2794)
							(mid -0.249642 -0.249642)
							(end -0.2794 -0.1778)
						)
						(arc
							(start -0.2794 0.1778)
							(mid -0.249642 0.249642)
							(end -0.1778 0.2794)
						)
						(arc
							(start 0.1778 0.2794)
							(mid 0.249642 0.249642)
							(end 0.2794 0.1778)
						)
						(arc
							(start 0.2794 -0.1778)
							(mid 0.249642 -0.249642)
							(end 0.1778 -0.2794)
						)
					)
					(width 0)
					(fill yes)
				)
			)
		)
	)
	(footprint ""
		(layer "F.Cu")
		(at 179.971446 -459.824836 180)
		(property "Reference" "R389"
			(at 0 0 180)
			(layer "F.SilkS")
			(hide yes)
			(effects
				(font
					(size 1.27 1.27)
				)
			)
		)
		(property "Value" "2KR2F-3-GP"
			(at 0.064008 -3.993896 180)
			(unlocked yes)
			(layer "F.Fab")
			(hide yes)
			(effects
				(font
					(size 1.016 1.016)
					(thickness 0.1524)
				)
			)
		)
		(property "Device Type" "R402H16"
			(at 0.064008 -5.517896 180)
			(unlocked yes)
			(layer "F.Fab")
			(hide yes)
			(effects
				(font
					(size 1.016 1.016)
					(thickness 0.1524)
				)
			)
		)
		(duplicate_pad_numbers_are_jumpers no)
		(fp_line
			(start 0.508 -0.9398)
			(end -0.508 -0.9398)
			(stroke
				(width 0.1524)
				(type default)
			)
			(layer "F.SilkS")
		)
		(fp_line
			(start -0.508 -0.9398)
			(end -0.508 0.9398)
			(stroke
				(width 0.1524)
				(type default)
			)
			(layer "F.SilkS")
		)
		(fp_rect
			(start -0.508 0.9398)
			(end 0.508 -0.9398)
			(stroke
				(width 0)
				(type default)
			)
			(fill no)
			(layer "F.CrtYd")
		)
		(fp_rect
			(start -0.508 0.9398)
			(end 0.508 -0.9398)
			(stroke
				(width 0)
				(type default)
			)
			(fill no)
			(layer "F.Fab")
		)
		(pad "1" smd custom
			(at 0 -0.4445 180)
			(size 0.1397 0.1397)
			(layers "F.Cu" "F.Mask" "F.Paste")
			(net "P12V_DIV")
			(options
				(clearance outline)
				(anchor circle)
			)
			(primitives
				(gr_poly
					(pts
						(arc
							(start -0.1778 -0.2794)
							(mid -0.249642 -0.249642)
							(end -0.2794 -0.1778)
						)
						(arc
							(start -0.2794 0.1778)
							(mid -0.249642 0.249642)
							(end -0.1778 0.2794)
						)
						(arc
							(start 0.1778 0.2794)
							(mid 0.249642 0.249642)
							(end 0.2794 0.1778)
						)
						(arc
							(start 0.2794 -0.1778)
							(mid 0.249642 -0.249642)
							(end 0.1778 -0.2794)
						)
					)
					(width 0)
					(fill yes)
				)
			)
		)
		(pad "2" smd custom
			(at 0 0.4445 180)
			(size 0.1397 0.1397)
			(layers "F.Cu" "F.Mask" "F.Paste")
			(net "GND")
			(options
				(clearance outline)
				(anchor circle)
			)
			(primitives
				(gr_poly
					(pts
						(arc
							(start -0.1778 -0.2794)
							(mid -0.249642 -0.249642)
							(end -0.2794 -0.1778)
						)
						(arc
							(start -0.2794 0.1778)
							(mid -0.249642 0.249642)
							(end -0.1778 0.2794)
						)
						(arc
							(start 0.1778 0.2794)
							(mid 0.249642 0.249642)
							(end 0.2794 0.1778)
						)
						(arc
							(start 0.2794 -0.1778)
							(mid 0.249642 -0.249642)
							(end 0.1778 -0.2794)
						)
					)
					(width 0)
					(fill yes)
				)
			)
		)
	)
	(footprint ""
		(layer "F.Cu")
		(at 45.465746 -29.9847 180)
		(property "Reference" "PC25"
			(at 0 0 180)
			(layer "F.SilkS")
			(hide yes)
			(effects
				(font
					(size 1.27 1.27)
				)
			)
		)
		(property "Value" "SC10U16V6KX-2GP"
			(at -0.0762 -5.1308 180)
			(unlocked yes)
			(layer "F.Fab")
			(hide yes)
			(effects
				(font
					(size 1.016 1.016)
					(thickness 0.1524)
				)
			)
		)
		(property "Device Type" "C1206H71"
			(at -0.127 -6.6548 180)
			(unlocked yes)
			(layer "F.Fab")
			(hide yes)
			(effects
				(font
					(size 1.016 1.016)
					(thickness 0.1524)
				)
			)
		)
		(duplicate_pad_numbers_are_jumpers no)
		(fp_line
			(start 1.016 2.2352)
			(end -1.016 2.2352)
			(stroke
				(width 0.1524)
				(type default)
			)
			(layer "F.SilkS")
		)
		(fp_line
			(start 1.016 0.8382)
			(end 1.016 2.2352)
			(stroke
				(width 0.1524)
				(type default)
			)
			(layer "F.SilkS")
		)
		(fp_line
			(start 1.016 -2.2352)
			(end 1.016 -0.8382)
			(stroke
				(width 0.1524)
				(type default)
			)
			(layer "F.SilkS")
		)
		(fp_line
			(start -1.016 2.2352)
			(end -1.016 0.8382)
			(stroke
				(width 0.1524)
				(type default)
			)
			(layer "F.SilkS")
		)
		(fp_line
			(start -1.016 -0.8382)
			(end -1.016 -2.2352)
			(stroke
				(width 0.1524)
				(type default)
			)
			(layer "F.SilkS")
		)
		(fp_line
			(start -1.016 -2.2352)
			(end 1.016 -2.2352)
			(stroke
				(width 0.1524)
				(type default)
			)
			(layer "F.SilkS")
		)
		(fp_rect
			(start -1.0922 2.3114)
			(end 1.0922 -2.3114)
			(stroke
				(width 0)
				(type default)
			)
			(fill no)
			(layer "F.CrtYd")
		)
		(fp_poly
			(pts
				(xy 1.0922 -2.3114) (xy 1.0922 2.3114) (xy -1.0922 2.3114) (xy -1.0922 -2.3114)
			)
			(stroke
				(width 0)
				(type default)
			)
			(fill no)
			(layer "F.Fab")
		)
		(pad "1" smd rect
			(at 0 -1.397 180)
			(size 1.651 1.27)
			(layers "F.Cu" "F.Mask" "F.Paste")
			(net "P5VB")
		)
		(pad "2" smd rect
			(at 0 1.397 180)
			(size 1.651 1.27)
			(layers "F.Cu" "F.Mask" "F.Paste")
			(net "GND")
		)
	)
	(footprint ""
		(layer "F.Cu")
		(at 43.814746 -212.118702 180)
		(property "Reference" "R281"
			(at 0 0 180)
			(layer "F.SilkS")
			(hide yes)
			(effects
				(font
					(size 1.27 1.27)
				)
			)
		)
		(property "Value" "0R2J-2-GP"
			(at 0.064008 -3.993896 180)
			(unlocked yes)
			(layer "F.Fab")
			(hide yes)
			(effects
				(font
					(size 1.016 1.016)
					(thickness 0.1524)
				)
			)
		)
		(property "Device Type" "R402H16"
			(at 0.064008 -5.517896 180)
			(unlocked yes)
			(layer "F.Fab")
			(hide yes)
			(effects
				(font
					(size 1.016 1.016)
					(thickness 0.1524)
				)
			)
		)
		(duplicate_pad_numbers_are_jumpers no)
		(fp_line
			(start 0.508 -0.9398)
			(end -0.508 -0.9398)
			(stroke
				(width 0.1524)
				(type default)
			)
			(layer "F.SilkS")
		)
		(fp_line
			(start -0.508 -0.9398)
			(end -0.508 0.9398)
			(stroke
				(width 0.1524)
				(type default)
			)
			(layer "F.SilkS")
		)
		(fp_rect
			(start -0.508 0.9398)
			(end 0.508 -0.9398)
			(stroke
				(width 0)
				(type default)
			)
			(fill no)
			(layer "F.CrtYd")
		)
		(fp_rect
			(start -0.508 0.9398)
			(end 0.508 -0.9398)
			(stroke
				(width 0)
				(type default)
			)
			(fill no)
			(layer "F.Fab")
		)
		(pad "1" smd custom
			(at 0 -0.4445 180)
			(size 0.1397 0.1397)
			(layers "F.Cu" "F.Mask" "F.Paste")
			(net "DRIVE_PWR12")
			(options
				(clearance outline)
				(anchor circle)
			)
			(primitives
				(gr_poly
					(pts
						(arc
							(start -0.1778 -0.2794)
							(mid -0.249642 -0.249642)
							(end -0.2794 -0.1778)
						)
						(arc
							(start -0.2794 0.1778)
							(mid -0.249642 0.249642)
							(end -0.1778 0.2794)
						)
						(arc
							(start 0.1778 0.2794)
							(mid 0.249642 0.249642)
							(end 0.2794 0.1778)
						)
						(arc
							(start 0.2794 -0.1778)
							(mid 0.249642 -0.249642)
							(end 0.1778 -0.2794)
						)
					)
					(width 0)
					(fill yes)
				)
			)
		)
		(pad "2" smd custom
			(at 0 0.4445 180)
			(size 0.1397 0.1397)
			(layers "F.Cu" "F.Mask" "F.Paste")
			(net "SW_PWR_HDD12")
			(options
				(clearance outline)
				(anchor circle)
			)
			(primitives
				(gr_poly
					(pts
						(arc
							(start -0.1778 -0.2794)
							(mid -0.249642 -0.249642)
							(end -0.2794 -0.1778)
						)
						(arc
							(start -0.2794 0.1778)
							(mid -0.249642 0.249642)
							(end -0.1778 0.2794)
						)
						(arc
							(start 0.1778 0.2794)
							(mid 0.249642 0.249642)
							(end 0.2794 0.1778)
						)
						(arc
							(start 0.2794 -0.1778)
							(mid 0.249642 -0.249642)
							(end 0.1778 -0.2794)
						)
					)
					(width 0)
					(fill yes)
				)
			)
		)
	)
	(footprint ""
		(layer "F.Cu")
		(at 237.870746 -27.9527)
		(property "Reference" "PR12"
			(at 0 0 0)
			(layer "F.SilkS")
			(hide yes)
			(effects
				(font
					(size 1.27 1.27)
				)
			)
		)
		(property "Value" "866KR2F-GP"
			(at 0.064008 -3.993896 0)
			(unlocked yes)
			(layer "F.Fab")
			(hide yes)
			(effects
				(font
					(size 1.016 1.016)
					(thickness 0.1524)
				)
			)
		)
		(property "Device Type" "R402H16"
			(at 0.064008 -5.517896 0)
			(unlocked yes)
			(layer "F.Fab")
			(hide yes)
			(effects
				(font
					(size 1.016 1.016)
					(thickness 0.1524)
				)
			)
		)
		(duplicate_pad_numbers_are_jumpers no)
		(fp_line
			(start -0.508 -0.9398)
			(end -0.508 0.9398)
			(stroke
				(width 0.1524)
				(type default)
			)
			(layer "F.SilkS")
		)
		(fp_line
			(start 0.508 -0.9398)
			(end -0.508 -0.9398)
			(stroke
				(width 0.1524)
				(type default)
			)
			(layer "F.SilkS")
		)
		(fp_rect
			(start -0.508 0.9398)
			(end 0.508 -0.9398)
			(stroke
				(width 0)
				(type default)
			)
			(fill no)
			(layer "F.CrtYd")
		)
		(fp_rect
			(start -0.508 0.9398)
			(end 0.508 -0.9398)
			(stroke
				(width 0)
				(type default)
			)
			(fill no)
			(layer "F.Fab")
		)
		(pad "1" smd custom
			(at 0 -0.4445)
			(size 0.1397 0.1397)
			(layers "F.Cu" "F.Mask" "F.Paste")
			(net "P5VA_VREG")
			(options
				(clearance outline)
				(anchor circle)
			)
			(primitives
				(gr_poly
					(pts
						(arc
							(start -0.1778 -0.2794)
							(mid -0.249642 -0.249642)
							(end -0.2794 -0.1778)
						)
						(arc
							(start -0.2794 0.1778)
							(mid -0.249642 0.249642)
							(end -0.1778 0.2794)
						)
						(arc
							(start 0.1778 0.2794)
							(mid 0.249642 0.249642)
							(end 0.2794 0.1778)
						)
						(arc
							(start 0.2794 -0.1778)
							(mid 0.249642 -0.249642)
							(end 0.1778 -0.2794)
						)
					)
					(width 0)
					(fill yes)
				)
			)
		)
		(pad "2" smd custom
			(at 0 0.4445)
			(size 0.1397 0.1397)
			(layers "F.Cu" "F.Mask" "F.Paste")
			(net "P5VA_RF")
			(options
				(clearance outline)
				(anchor circle)
			)
			(primitives
				(gr_poly
					(pts
						(arc
							(start -0.1778 -0.2794)
							(mid -0.249642 -0.249642)
							(end -0.2794 -0.1778)
						)
						(arc
							(start -0.2794 0.1778)
							(mid -0.249642 0.249642)
							(end -0.1778 0.2794)
						)
						(arc
							(start 0.1778 0.2794)
							(mid 0.249642 0.249642)
							(end 0.2794 0.1778)
						)
						(arc
							(start 0.2794 -0.1778)
							(mid 0.249642 -0.249642)
							(end 0.1778 -0.2794)
						)
					)
					(width 0)
					(fill yes)
				)
			)
		)
	)
)
